(kicad_pcb
	(version 20241229)
	(generator "pcbnew")
	(generator_version "9.0")
	(general
		(thickness 1.6296)
		(legacy_teardrops no)
	)
	(paper "A3")
	(title_block
		(title "Thunderbolt to 10GbE adapter")
		(date "2026-04-21")
		(rev "1.1.0")
		(company "Antmicro Ltd")
		(comment 1 "www.antmicro.com")
		(comment 9 "footprints 183-187 of 703")
	)
	(layers
		(0 "F.Cu" signal)
		(4 "In1.Cu" signal)
		(6 "In2.Cu" signal)
		(8 "In3.Cu" signal)
		(10 "In4.Cu" signal)
		(12 "In5.Cu" signal)
		(14 "In6.Cu" signal)
		(2 "B.Cu" signal)
		(9 "F.Adhes" user "F.Adhesive")
		(11 "B.Adhes" user "B.Adhesive")
		(13 "F.Paste" user)
		(15 "B.Paste" user)
		(5 "F.SilkS" user "F.Silkscreen")
		(7 "B.SilkS" user "B.Silkscreen")
		(1 "F.Mask" user)
		(3 "B.Mask" user)
		(17 "Dwgs.User" user "User.Drawings")
		(19 "Cmts.User" user "User.Comments")
		(21 "Eco1.User" user "User.Eco1")
		(23 "Eco2.User" user "User.Eco2")
		(25 "Edge.Cuts" user)
		(27 "Margin" user)
		(31 "F.CrtYd" user "F.Courtyard")
		(29 "B.CrtYd" user "B.Courtyard")
		(35 "F.Fab" user)
		(33 "B.Fab" user)
	)
	(footprint "antmicro-footprints:R_0402_1005Metric"
		(layer "F.Cu")
		(at 116.4 108.1)
		(descr "Resistor SMD 0402")
		(tags "resistor SMD 0402")
		(property "Reference" "R7"
			(at 0 -8.1 0)
			(layer "F.SilkS")
			(effects
				(font
					(size 0.7 0.7)
					(thickness 0.15)
				)
			)
		)
		(property "Value" "R_10k_0402"
			(at -1.011843 1.772047 0)
			(layer "F.Fab")
			(effects
				(font
					(size 0.7 0.7)
					(thickness 0.15)
				)
				(justify left bottom)
			)
		)
		(property "Datasheet" "https://www.bourns.com/docs/product-datasheets/cr.pdf"
			(at 0 0 0)
			(layer "F.Fab")
			(hide yes)
			(effects
				(font
					(size 1.27 1.27)
					(thickness 0.15)
				)
			)
		)
		(property "Description" "SMD Chip Resistor, 10 kohm, ± 1%, 62.5 mW, 0402 [1005 Metric], Thick Film, General Purpose"
			(at 0 0 0)
			(layer "F.Fab")
			(hide yes)
			(effects
				(font
					(size 1.27 1.27)
					(thickness 0.15)
				)
			)
		)
		(property "MPN" "CR0402-FX-1002GLF"
			(at 0 0 0)
			(unlocked yes)
			(layer "F.Fab")
			(hide yes)
			(effects
				(font
					(size 1 1)
					(thickness 0.15)
				)
			)
		)
		(property "Manufacturer" "Bourns"
			(at 0 0 0)
			(unlocked yes)
			(layer "F.Fab")
			(hide yes)
			(effects
				(font
					(size 1 1)
					(thickness 0.15)
				)
			)
		)
		(property "License" "Apache-2.0"
			(at 0 0 0)
			(unlocked yes)
			(layer "F.Fab")
			(hide yes)
			(effects
				(font
					(size 1 1)
					(thickness 0.15)
				)
			)
		)
		(property "Val" "10k"
			(at 0 0 0)
			(unlocked yes)
			(layer "F.Fab")
			(hide yes)
			(effects
				(font
					(size 1 1)
					(thickness 0.15)
				)
			)
		)
		(property "Tolerance" "1%"
			(at 0 0 0)
			(unlocked yes)
			(layer "F.Fab")
			(hide yes)
			(effects
				(font
					(size 1 1)
					(thickness 0.15)
				)
			)
		)
		(property "Author" "Antmicro"
			(at 0 0 0)
			(unlocked yes)
			(layer "F.Fab")
			(hide yes)
			(effects
				(font
					(size 1 1)
					(thickness 0.15)
				)
			)
		)
		(sheetname "/PD and TB DC-DC/")
		(sheetfile "PD_and_TB_DC_DC.kicad_sch")
		(attr smd)
		(fp_rect
			(start -0.925 -0.47)
			(end 0.925 0.47)
			(stroke
				(width 0.05)
				(type default)
			)
			(fill no)
			(layer "F.CrtYd")
		)
		(fp_rect
			(start -0.5 -0.25)
			(end 0.5 0.25)
			(stroke
				(width 0.15)
				(type solid)
			)
			(fill no)
			(layer "F.Fab")
		)
		(fp_text user "Author: Antmicro"
			(at -0.95 4.169 0)
			(layer "F.Fab")
			(effects
				(font
					(size 0.7 0.7)
					(thickness 0.15)
				)
				(justify left bottom)
			)
		)
		(fp_text user "${REFERENCE}"
			(at -0.95 3.168 0)
			(layer "F.Fab")
			(effects
				(font
					(size 0.7 0.7)
					(thickness 0.15)
				)
				(justify left bottom)
			)
		)
		(fp_text user "License: Apache-2.0"
			(at -0.95 5.169 0)
			(layer "F.Fab")
			(effects
				(font
					(size 0.7 0.7)
					(thickness 0.15)
				)
				(justify left bottom)
			)
		)
		(pad "1" smd roundrect
			(at -0.48 0)
			(size 0.59 0.64)
			(layers "F.Cu" "F.Mask" "F.Paste")
			(roundrect_rratio 0.25)
			(net 23 "GND")
			(pintype "passive")
		)
		(pad "2" smd roundrect
			(at 0.48 0)
			(size 0.59 0.64)
			(layers "F.Cu" "F.Mask" "F.Paste")
			(roundrect_rratio 0.25)
			(net 413 "Net-(D3-C)")
			(pintype "passive")
		)
	)
	(footprint "antmicro-footprints:R_0402_1005Metric"
		(layer "F.Cu")
		(at 139 68.5)
		(descr "Resistor SMD 0402")
		(tags "resistor SMD 0402")
		(property "Reference" "R114"
			(at 1 0.450001 0)
			(layer "F.SilkS")
			(effects
				(font
					(size 0.7 0.7)
					(thickness 0.15)
				)
				(justify left bottom)
			)
		)
		(property "Value" "R_0R_0402"
			(at -1.011843 1.772047 0)
			(layer "F.Fab")
			(effects
				(font
					(size 0.7 0.7)
					(thickness 0.15)
				)
				(justify left bottom)
			)
		)
		(property "Datasheet" "https://industrial.panasonic.com/cdbs/www-data/pdf/RDA0000/AOA0000C301.pdf"
			(at 0 0 0)
			(layer "F.Fab")
			(hide yes)
			(effects
				(font
					(size 1.27 1.27)
					(thickness 0.15)
				)
			)
		)
		(property "Description" "SMD Chip Resistor, Jumper, 0 ohm, 100 mW, 0402 [1005 Metric], Thick Film, General Purpose"
			(at 0 0 0)
			(layer "F.Fab")
			(hide yes)
			(effects
				(font
					(size 1.27 1.27)
					(thickness 0.15)
				)
			)
		)
		(property "MPN" "ERJ2GE0R00X"
			(at 0 0 0)
			(unlocked yes)
			(layer "F.Fab")
			(hide yes)
			(effects
				(font
					(size 1 1)
					(thickness 0.15)
				)
			)
		)
		(property "Manufacturer" "Panasonic"
			(at 0 0 0)
			(unlocked yes)
			(layer "F.Fab")
			(hide yes)
			(effects
				(font
					(size 1 1)
					(thickness 0.15)
				)
			)
		)
		(property "License" "Apache-2.0"
			(at 0 0 0)
			(unlocked yes)
			(layer "F.Fab")
			(hide yes)
			(effects
				(font
					(size 1 1)
					(thickness 0.15)
				)
			)
		)
		(property "Author" "Antmicro"
			(at 0 0 0)
			(unlocked yes)
			(layer "F.Fab")
			(hide yes)
			(effects
				(font
					(size 1 1)
					(thickness 0.15)
				)
			)
		)
		(property "Val" "0R"
			(at 0 0 0)
			(unlocked yes)
			(layer "F.Fab")
			(hide yes)
			(effects
				(font
					(size 1 1)
					(thickness 0.15)
				)
			)
		)
		(property "Tolerance" "~"
			(at 0 0 0)
			(unlocked yes)
			(layer "F.Fab")
			(hide yes)
			(effects
				(font
					(size 1 1)
					(thickness 0.15)
				)
			)
		)
		(property "Current" "1A"
			(at 0 0 0)
			(unlocked yes)
			(layer "F.Fab")
			(hide yes)
			(effects
				(font
					(size 1 1)
					(thickness 0.15)
				)
			)
		)
		(sheetname "/X710-AT2 PCIe/")
		(sheetfile "x710-at2-pcie.kicad_sch")
		(attr smd)
		(fp_rect
			(start -0.925 -0.47)
			(end 0.925 0.47)
			(stroke
				(width 0.05)
				(type default)
			)
			(fill no)
			(layer "F.CrtYd")
		)
		(fp_rect
			(start -0.5 -0.25)
			(end 0.5 0.25)
			(stroke
				(width 0.15)
				(type solid)
			)
			(fill no)
			(layer "F.Fab")
		)
		(fp_text user "License: Apache-2.0"
			(at -0.95 5.169 0)
			(layer "F.Fab")
			(effects
				(font
					(size 0.7 0.7)
					(thickness 0.15)
				)
				(justify left bottom)
			)
		)
		(fp_text user "Author: Antmicro"
			(at -0.95 4.169 0)
			(layer "F.Fab")
			(effects
				(font
					(size 0.7 0.7)
					(thickness 0.15)
				)
				(justify left bottom)
			)
		)
		(fp_text user "${REFERENCE}"
			(at -0.95 3.168 0)
			(layer "F.Fab")
			(effects
				(font
					(size 0.7 0.7)
					(thickness 0.15)
				)
				(justify left bottom)
			)
		)
		(pad "1" smd roundrect
			(at -0.48 0)
			(size 0.59 0.64)
			(layers "F.Cu" "F.Mask" "F.Paste")
			(roundrect_rratio 0.25)
			(net 394 "/TB Controller/REFCLK.-")
			(pintype "passive")
		)
		(pad "2" smd roundrect
			(at 0.48 0)
			(size 0.59 0.64)
			(layers "F.Cu" "F.Mask" "F.Paste")
			(roundrect_rratio 0.25)
			(net 160 "/X710-AT2 PCIe/CLK-")
			(pintype "passive")
		)
	)
	(footprint "antmicro-footprints:SOT-23-6"
		(layer "F.Cu")
		(at 142.25 61.25 90)
		(property "Reference" "U21"
			(at -0.55 -2.05 90)
			(layer "F.SilkS")
			(effects
				(font
					(size 0.7 0.7)
					(thickness 0.15)
				)
				(justify left bottom)
			)
		)
		(property "Value" "LTC4412IS6"
			(at -1.75 2.693 90)
			(layer "F.Fab")
			(effects
				(font
					(size 0.7 0.7)
					(thickness 0.15)
				)
				(justify left bottom)
			)
		)
		(property "Datasheet" "https://www.analog.com/media/en/technical-documentation/data-sheets/4412fb.pdf"
			(at 0 -0.057 90)
			(layer "F.Fab")
			(hide yes)
			(effects
				(font
					(size 1.27 1.27)
					(thickness 0.15)
				)
			)
		)
		(property "Description" "Ideal diode controller"
			(at 0 -0.057 90)
			(layer "F.Fab")
			(hide yes)
			(effects
				(font
					(size 1.27 1.27)
					(thickness 0.15)
				)
			)
		)
		(property "MPN" "LTC4412IS6#TRMPBF"
			(at 0 0 90)
			(unlocked yes)
			(layer "F.Fab")
			(hide yes)
			(effects
				(font
					(size 1 1)
					(thickness 0.15)
				)
			)
		)
		(property "Manufacturer" "Analog Devices"
			(at 0 0 90)
			(unlocked yes)
			(layer "F.Fab")
			(hide yes)
			(effects
				(font
					(size 1 1)
					(thickness 0.15)
				)
			)
		)
		(property "Author" "Antmicro"
			(at 0 0 90)
			(unlocked yes)
			(layer "F.Fab")
			(hide yes)
			(effects
				(font
					(size 1 1)
					(thickness 0.15)
				)
			)
		)
		(property "License" "Apache-2.0"
			(at 0 0 90)
			(unlocked yes)
			(layer "F.Fab")
			(hide yes)
			(effects
				(font
					(size 1 1)
					(thickness 0.15)
				)
			)
		)
		(sheetname "/Power input/")
		(sheetfile "power_input.kicad_sch")
		(attr smd)
		(fp_line
			(start 1.45 -0.757)
			(end 1.45 -0.457)
			(stroke
				(width 0.12)
				(type solid)
			)
			(layer "F.SilkS")
		)
		(fp_line
			(start 1.3 -0.757)
			(end 1.45 -0.757)
			(stroke
				(width 0.12)
				(type solid)
			)
			(layer "F.SilkS")
		)
		(fp_line
			(start -1.3 -0.757)
			(end -1.45 -0.757)
			(stroke
				(width 0.12)
				(type solid)
			)
			(layer "F.SilkS")
		)
		(fp_line
			(start -1.45 -0.757)
			(end -1.45 -0.457)
			(stroke
				(width 0.12)
				(type solid)
			)
			(layer "F.SilkS")
		)
		(fp_line
			(start 1.45 0.643)
			(end 1.45 0.343)
			(stroke
				(width 0.12)
				(type solid)
			)
			(layer "F.SilkS")
		)
		(fp_line
			(start 1.3 0.643)
			(end 1.45 0.643)
			(stroke
				(width 0.12)
				(type solid)
			)
			(layer "F.SilkS")
		)
		(fp_line
			(start -1.45 0.643)
			(end -1.45 0.343)
			(stroke
				(width 0.12)
				(type solid)
			)
			(layer "F.SilkS")
		)
		(fp_rect
			(start -1.55 -1.85)
			(end 1.55 1.75)
			(stroke
				(width 0.05)
				(type solid)
			)
			(fill no)
			(layer "F.CrtYd")
		)
		(fp_line
			(start 1.5 -0.757)
			(end 1.5 0.643)
			(stroke
				(width 0.1)
				(type solid)
			)
			(layer "F.Fab")
		)
		(fp_line
			(start -1.5 -0.757)
			(end 1.5 -0.757)
			(stroke
				(width 0.1)
				(type solid)
			)
			(layer "F.Fab")
		)
		(fp_line
			(start 1.5 0.643)
			(end -1.5 0.643)
			(stroke
				(width 0.1)
				(type solid)
			)
			(layer "F.Fab")
		)
		(fp_line
			(start -1.5 0.643)
			(end -1.5 -0.757)
			(stroke
				(width 0.1)
				(type solid)
			)
			(layer "F.Fab")
		)
		(fp_text user "."
			(at -1.4 1.143 270)
			(layer "F.SilkS")
			(effects
				(font
					(size 1 1)
					(thickness 0.15)
				)
			)
		)
		(fp_text user "${REFERENCE}"
			(at -1.75 4 90)
			(layer "F.Fab")
			(effects
				(font
					(size 0.7 0.7)
					(thickness 0.15)
				)
				(justify left bottom)
			)
		)
		(fp_text user "License: Apache-2.0"
			(at -1.75 6.5 90)
			(layer "F.Fab")
			(effects
				(font
					(size 0.7 0.7)
					(thickness 0.15)
				)
				(justify left bottom)
			)
		)
		(fp_text user "Author: Antmicro"
			(at -1.829 5.25 90)
			(layer "F.Fab")
			(effects
				(font
					(size 0.7 0.7)
					(thickness 0.15)
				)
				(justify left bottom)
			)
		)
		(pad "1" smd roundrect
			(at -0.954 1.1 90)
			(size 0.55 1)
			(layers "F.Cu" "F.Mask" "F.Paste")
			(roundrect_rratio 0.15)
			(net 13 "/Power input/5V_JACK")
			(pinfunction "IN")
			(pintype "power_in")
		)
		(pad "2" smd roundrect
			(at -0.003 1.1 90)
			(size 0.55 1)
			(layers "F.Cu" "F.Mask" "F.Paste")
			(roundrect_rratio 0.15)
			(net 23 "GND")
			(pinfunction "GND")
			(pintype "power_in")
		)
		(pad "3" smd roundrect
			(at 0.947 1.1 90)
			(size 0.55 1)
			(layers "F.Cu" "F.Mask" "F.Paste")
			(roundrect_rratio 0.15)
			(net 23 "GND")
			(pinfunction "CTL")
			(pintype "input")
		)
		(pad "4" smd roundrect
			(at 0.947 -1.214 90)
			(size 0.55 1)
			(layers "F.Cu" "F.Mask" "F.Paste")
			(roundrect_rratio 0.15)
			(net 593 "unconnected-(U21-STAT-Pad4)")
			(pinfunction "STAT")
			(pintype "output+no_connect")
		)
		(pad "5" smd roundrect
			(at -0.003 -1.214 90)
			(size 0.55 1)
			(layers "F.Cu" "F.Mask" "F.Paste")
			(roundrect_rratio 0.15)
			(net 432 "Net-(Q7-G)")
			(pinfunction "GATE")
			(pintype "output")
		)
		(pad "6" smd roundrect
			(at -0.954 -1.214 90)
			(size 0.55 1)
			(layers "F.Cu" "F.Mask" "F.Paste")
			(roundrect_rratio 0.15)
			(net 40 "+5V")
			(pinfunction "SENSE")
			(pintype "input")
		)
	)
	(footprint "antmicro-footprints:C_2220_5650Metric"
		(layer "F.Cu")
		(at 149 51 90)
		(descr "Capacitor SMD 2220")
		(tags "capacitor SMD 2220")
		(property "Reference" "C313"
			(at 3.6 -3 180)
			(layer "F.SilkS")
			(effects
				(font
					(size 0.7 0.7)
					(thickness 0.15)
				)
				(justify left bottom)
			)
		)
		(property "Value" "C_22u_100V_2220"
			(at 0 3.9 90)
			(layer "F.Fab")
			(effects
				(font
					(size 0.7 0.7)
					(thickness 0.15)
				)
				(justify left bottom)
			)
		)
		(property "Datasheet" "https://product.tdk.com/en/search/capacitor/ceramic/mlcc/info?part_no=C5750X7S2A226M280KB"
			(at 0 0 90)
			(layer "F.Fab")
			(hide yes)
			(effects
				(font
					(size 1.27 1.27)
					(thickness 0.15)
				)
			)
		)
		(property "Description" "SMT Multilayer Ceramic Capacitor, 22 µF, 100 V, 2220 [5750 Metric], ± 20%, X7S, C"
			(at 0 0 90)
			(layer "F.Fab")
			(hide yes)
			(effects
				(font
					(size 1.27 1.27)
					(thickness 0.15)
				)
			)
		)
		(property "MPN" "C5750X7S2A226M280KB"
			(at 0 0 90)
			(unlocked yes)
			(layer "F.Fab")
			(hide yes)
			(effects
				(font
					(size 1 1)
					(thickness 0.15)
				)
			)
		)
		(property "Manufacturer" "TDK"
			(at 0 0 90)
			(unlocked yes)
			(layer "F.Fab")
			(hide yes)
			(effects
				(font
					(size 1 1)
					(thickness 0.15)
				)
			)
		)
		(property "License" "Apache-2.0"
			(at 0 0 90)
			(unlocked yes)
			(layer "F.Fab")
			(hide yes)
			(effects
				(font
					(size 1 1)
					(thickness 0.15)
				)
			)
		)
		(property "Author" "Antmicro"
			(at 0 0 90)
			(unlocked yes)
			(layer "F.Fab")
			(hide yes)
			(effects
				(font
					(size 1 1)
					(thickness 0.15)
				)
			)
		)
		(property "Val" "22u"
			(at 0 0 90)
			(unlocked yes)
			(layer "F.Fab")
			(hide yes)
			(effects
				(font
					(size 1 1)
					(thickness 0.15)
				)
			)
		)
		(property "Voltage" "100V"
			(at 0 0 90)
			(unlocked yes)
			(layer "F.Fab")
			(hide yes)
			(effects
				(font
					(size 1 1)
					(thickness 0.15)
				)
			)
		)
		(property "Dielectric" "X7S"
			(at 0 0 90)
			(unlocked yes)
			(layer "F.Fab")
			(hide yes)
			(effects
				(font
					(size 1 1)
					(thickness 0.15)
				)
			)
		)
		(property "Public" "False"
			(at 0 0 90)
			(unlocked yes)
			(layer "F.Fab")
			(hide yes)
			(effects
				(font
					(size 1 1)
					(thickness 0.15)
				)
			)
		)
		(sheetname "/Power input/")
		(sheetfile "power_input.kicad_sch")
		(attr smd)
		(fp_line
			(start -1.415 -2.61)
			(end 1.415 -2.61)
			(stroke
				(width 0.15)
				(type solid)
			)
			(layer "F.SilkS")
		)
		(fp_line
			(start -1.415 2.61)
			(end 1.415 2.61)
			(stroke
				(width 0.15)
				(type solid)
			)
			(layer "F.SilkS")
		)
		(fp_rect
			(start -3.7 -2.95)
			(end 3.7 2.95)
			(stroke
				(width 0.05)
				(type solid)
			)
			(fill no)
			(layer "F.CrtYd")
		)
		(fp_rect
			(start -2.85 -2.5)
			(end 2.85 2.5)
			(stroke
				(width 0.15)
				(type solid)
			)
			(fill no)
			(layer "F.Fab")
		)
		(fp_text user "License: Apache-2.0"
			(at -3.7 6.9 90)
			(layer "F.Fab")
			(effects
				(font
					(size 0.7 0.7)
					(thickness 0.15)
				)
				(justify left bottom)
			)
		)
		(fp_text user "${REFERENCE}"
			(at -3.7 5.9 90)
			(layer "F.Fab")
			(effects
				(font
					(size 0.7 0.7)
					(thickness 0.15)
				)
				(justify left bottom)
			)
		)
		(fp_text user "Author: Antmicro"
			(at -3.7 7.9 90)
			(layer "F.Fab")
			(effects
				(font
					(size 0.7 0.7)
					(thickness 0.15)
				)
				(justify left bottom)
			)
		)
		(pad "1" smd roundrect
			(at -2.55 0 90)
			(size 1.8 5.4)
			(layers "F.Cu" "F.Mask" "F.Paste")
			(roundrect_rratio 0.138889)
			(net 23 "GND")
			(pintype "passive")
		)
		(pad "2" smd roundrect
			(at 2.55 0 90)
			(size 1.8 5.4)
			(layers "F.Cu" "F.Mask" "F.Paste")
			(roundrect_rratio 0.138889)
			(net 412 "Net-(D15-C)")
			(pintype "passive")
		)
	)
	(footprint "antmicro-footprints:R_0402_1005Metric"
		(layer "F.Cu")
		(at 117 70.9)
		(descr "Resistor SMD 0402")
		(tags "resistor SMD 0402")
		(property "Reference" "R222"
			(at 3.6 -10.5 0)
			(layer "F.SilkS")
			(effects
				(font
					(size 0.7 0.7)
					(thickness 0.15)
				)
				(justify left bottom)
			)
		)
		(property "Value" "R_10k_0402"
			(at -1.011843 1.772047 0)
			(layer "F.Fab")
			(effects
				(font
					(size 0.7 0.7)
					(thickness 0.15)
				)
				(justify left bottom)
			)
		)
		(property "Datasheet" "https://www.bourns.com/docs/product-datasheets/cr.pdf"
			(at 0 0 0)
			(layer "F.Fab")
			(hide yes)
			(effects
				(font
					(size 1.27 1.27)
					(thickness 0.15)
				)
			)
		)
		(property "Description" "SMD Chip Resistor, 10 kohm, ± 1%, 62.5 mW, 0402 [1005 Metric], Thick Film, General Purpose"
			(at 0 0 0)
			(layer "F.Fab")
			(hide yes)
			(effects
				(font
					(size 1.27 1.27)
					(thickness 0.15)
				)
			)
		)
		(property "MPN" "CR0402-FX-1002GLF"
			(at 0 0 0)
			(unlocked yes)
			(layer "F.Fab")
			(hide yes)
			(effects
				(font
					(size 1 1)
					(thickness 0.15)
				)
			)
		)
		(property "Manufacturer" "Bourns"
			(at 0 0 0)
			(unlocked yes)
			(layer "F.Fab")
			(hide yes)
			(effects
				(font
					(size 1 1)
					(thickness 0.15)
				)
			)
		)
		(property "License" "Apache-2.0"
			(at 0 0 0)
			(unlocked yes)
			(layer "F.Fab")
			(hide yes)
			(effects
				(font
					(size 1 1)
					(thickness 0.15)
				)
			)
		)
		(property "Author" "Antmicro"
			(at 0 0 0)
			(unlocked yes)
			(layer "F.Fab")
			(hide yes)
			(effects
				(font
					(size 1 1)
					(thickness 0.15)
				)
			)
		)
		(property "Val" "10k"
			(at 0 0 0)
			(unlocked yes)
			(layer "F.Fab")
			(hide yes)
			(effects
				(font
					(size 1 1)
					(thickness 0.15)
				)
			)
		)
		(property "Tolerance" "1%"
			(at 0 0 0)
			(unlocked yes)
			(layer "F.Fab")
			(hide yes)
			(effects
				(font
					(size 1 1)
					(thickness 0.15)
				)
			)
		)
		(sheetname "/Fan controller/")
		(sheetfile "fan-controller.kicad_sch")
		(attr smd)
		(fp_rect
			(start -0.925 -0.47)
			(end 0.925 0.47)
			(stroke
				(width 0.05)
				(type default)
			)
			(fill no)
			(layer "F.CrtYd")
		)
		(fp_rect
			(start -0.5 -0.25)
			(end 0.5 0.25)
			(stroke
				(width 0.15)
				(type solid)
			)
			(fill no)
			(layer "F.Fab")
		)
		(fp_text user "Author: Antmicro"
			(at -0.95 4.169 0)
			(layer "F.Fab")
			(effects
				(font
					(size 0.7 0.7)
					(thickness 0.15)
				)
				(justify left bottom)
			)
		)
		(fp_text user "${REFERENCE}"
			(at -0.95 3.168 0)
			(layer "F.Fab")
			(effects
				(font
					(size 0.7 0.7)
					(thickness 0.15)
				)
				(justify left bottom)
			)
		)
		(fp_text user "License: Apache-2.0"
			(at -0.95 5.169 0)
			(layer "F.Fab")
			(effects
				(font
					(size 0.7 0.7)
					(thickness 0.15)
				)
				(justify left bottom)
			)
		)
		(pad "1" smd roundrect
			(at -0.48 0)
			(size 0.59 0.64)
			(layers "F.Cu" "F.Mask" "F.Paste")
			(roundrect_rratio 0.25)
			(net 23 "GND")
			(pintype "passive")
		)
		(pad "2" smd roundrect
			(at 0.48 0)
			(size 0.59 0.64)
			(layers "F.Cu" "F.Mask" "F.Paste")
			(roundrect_rratio 0.25)
			(net 158 "/Fan controller/SLOPE")
			(pintype "passive")
		)
	)
)
